(kicad_pcb
	(version 20260206)
	(generator "pcbnew")
	(generator_version "10.0")
	(general
		(thickness 1.6)
		(legacy_teardrops no)
	)
	(paper "A4")
	(title_block
		(title "04192023_DAF0TMB3IC0_F0TG_MB_C_brd_V02_OCP.brd")
		(comment 1 "Grand Teton / footprints 5244-5249 of 8354")
	)
	(layers
		(0 "F.Cu" signal "TOP")
		(4 "In1.Cu" signal "GND")
		(6 "In2.Cu" signal "IN1")
		(8 "In3.Cu" signal "GND1")
		(10 "In4.Cu" signal "IN2")
		(12 "In5.Cu" signal "GND2")
		(14 "In6.Cu" signal "IN3")
		(16 "In7.Cu" signal "GND3")
		(18 "In8.Cu" signal "VCC")
		(20 "In9.Cu" signal "VCC1")
		(22 "In10.Cu" signal "GND4")
		(24 "In11.Cu" signal "IN4")
		(26 "In12.Cu" signal "GND5")
		(28 "In13.Cu" signal "IN5")
		(30 "In14.Cu" signal "GND6")
		(32 "In15.Cu" signal "IN6")
		(34 "In16.Cu" signal "GND7")
		(2 "B.Cu" signal "BOTTOM")
		(9 "F.Adhes" user "F.Adhesive")
		(11 "B.Adhes" user "B.Adhesive")
		(13 "F.Paste" user "Package Geometry/Pastemask Top")
		(15 "B.Paste" user "Package Geometry/Pastemask Bottom")
		(5 "F.SilkS" user "Ref Des/Silkscreen Top")
		(7 "B.SilkS" user "Ref Des/Silkscreen Bottom")
		(1 "F.Mask" user "Board Geometry/Soldermask Top")
		(3 "B.Mask" user "Board Geometry/Soldermask Bottom")
		(17 "Dwgs.User" user "User.Drawings")
		(19 "Cmts.User" user "User.Comments")
		(21 "Eco1.User" user "User.Eco1")
		(23 "Eco2.User" user "User.Eco2")
		(25 "Edge.Cuts" user "Board Geometry/Outline")
		(27 "Margin" user)
		(31 "F.CrtYd" user "Package Geometry/Place Bound Top")
		(29 "B.CrtYd" user "Package Geometry/Place Bound Bottom")
		(35 "F.Fab" user "Ref Des/Assembly Top")
		(33 "B.Fab" user "Ref Des/Assembly Bottom")
	)
	(footprint ""
		(layer "B.Cu")
		(at 365.835692 -255.554988)
		(property "Reference" "C2152"
			(at 0 0 0)
			(layer "B.SilkS")
			(hide yes)
			(effects
				(font
					(size 1.27 1.27)
				)
				(justify mirror)
			)
		)
		(property "Value" ""
			(at 0 0 0)
			(layer "B.Fab")
			(effects
				(font
					(size 1.27 1.27)
				)
				(justify mirror)
			)
		)
		(duplicate_pad_numbers_are_jumpers no)
		(fp_line
			(start -0.7874 -0.4064)
			(end -0.7874 0.4064)
			(stroke
				(width 0.1524)
				(type default)
			)
			(layer "B.SilkS")
		)
		(fp_line
			(start -0.7874 0.4064)
			(end 0.7874 0.4064)
			(stroke
				(width 0.1524)
				(type default)
			)
			(layer "B.SilkS")
		)
		(fp_line
			(start 0.7874 -0.4064)
			(end -0.7874 -0.4064)
			(stroke
				(width 0.1524)
				(type default)
			)
			(layer "B.SilkS")
		)
		(fp_line
			(start 0.7874 0.4064)
			(end 0.7874 -0.4064)
			(stroke
				(width 0.1524)
				(type default)
			)
			(layer "B.SilkS")
		)
		(fp_line
			(start -0.67945 -0.3048)
			(end -0.67945 0.3048)
			(stroke
				(width 0.1)
				(type default)
			)
			(layer "B.Fab")
		)
		(fp_line
			(start -0.67945 0.3048)
			(end -0.120396 0.3048)
			(stroke
				(width 0.1)
				(type default)
			)
			(layer "B.Fab")
		)
		(fp_line
			(start -0.12065 -0.3048)
			(end -0.67945 -0.3048)
			(stroke
				(width 0.1)
				(type default)
			)
			(layer "B.Fab")
		)
		(fp_line
			(start -0.12065 -0.2794)
			(end -0.12065 -0.3048)
			(stroke
				(width 0.1)
				(type default)
			)
			(layer "B.Fab")
		)
		(fp_line
			(start -0.120396 0.2794)
			(end 0.12065 0.2794)
			(stroke
				(width 0.1)
				(type default)
			)
			(layer "B.Fab")
		)
		(fp_line
			(start -0.120396 0.3048)
			(end -0.120396 0.2794)
			(stroke
				(width 0.1)
				(type default)
			)
			(layer "B.Fab")
		)
		(fp_line
			(start 0.12065 -0.305054)
			(end 0.12065 -0.2794)
			(stroke
				(width 0.1)
				(type default)
			)
			(layer "B.Fab")
		)
		(fp_line
			(start 0.12065 -0.2794)
			(end -0.12065 -0.2794)
			(stroke
				(width 0.1)
				(type default)
			)
			(layer "B.Fab")
		)
		(fp_line
			(start 0.12065 0.2794)
			(end 0.12065 0.3048)
			(stroke
				(width 0.1)
				(type default)
			)
			(layer "B.Fab")
		)
		(fp_line
			(start 0.12065 0.3048)
			(end 0.67945 0.3048)
			(stroke
				(width 0.1)
				(type default)
			)
			(layer "B.Fab")
		)
		(fp_line
			(start 0.67945 -0.305054)
			(end 0.12065 -0.305054)
			(stroke
				(width 0.1)
				(type default)
			)
			(layer "B.Fab")
		)
		(fp_line
			(start 0.67945 0.3048)
			(end 0.67945 -0.305054)
			(stroke
				(width 0.1)
				(type default)
			)
			(layer "B.Fab")
		)
		(pad "1" smd circle
			(at 0.40005 0 180)
			(size 0 0)
			(layers "B.Cu" "B.Mask" "B.Paste")
			(net "PVDDCR_SOC_P0")
		)
		(pad "2" smd circle
			(at -0.40005 0 180)
			(size 0 0)
			(layers "B.Cu" "B.Mask" "B.Paste")
			(net "GND")
		)
	)
	(footprint ""
		(layer "B.Cu")
		(at 238.310928 -289.828732)
		(property "Reference" "C6758"
			(at 0 0 0)
			(layer "B.SilkS")
			(hide yes)
			(effects
				(font
					(size 1.27 1.27)
				)
				(justify mirror)
			)
		)
		(property "Value" ""
			(at 0 0 0)
			(layer "B.Fab")
			(effects
				(font
					(size 1.27 1.27)
				)
				(justify mirror)
			)
		)
		(duplicate_pad_numbers_are_jumpers no)
		(fp_line
			(start -0.7874 -0.4064)
			(end -0.7874 0.4064)
			(stroke
				(width 0.1524)
				(type default)
			)
			(layer "B.SilkS")
		)
		(fp_line
			(start -0.7874 0.4064)
			(end 0.7874 0.4064)
			(stroke
				(width 0.1524)
				(type default)
			)
			(layer "B.SilkS")
		)
		(fp_line
			(start 0.7874 -0.4064)
			(end -0.7874 -0.4064)
			(stroke
				(width 0.1524)
				(type default)
			)
			(layer "B.SilkS")
		)
		(fp_line
			(start 0.7874 0.4064)
			(end 0.7874 -0.4064)
			(stroke
				(width 0.1524)
				(type default)
			)
			(layer "B.SilkS")
		)
		(fp_line
			(start -0.67945 -0.3048)
			(end -0.67945 0.3048)
			(stroke
				(width 0.1)
				(type default)
			)
			(layer "B.Fab")
		)
		(fp_line
			(start -0.67945 0.3048)
			(end -0.120396 0.3048)
			(stroke
				(width 0.1)
				(type default)
			)
			(layer "B.Fab")
		)
		(fp_line
			(start -0.12065 -0.3048)
			(end -0.67945 -0.3048)
			(stroke
				(width 0.1)
				(type default)
			)
			(layer "B.Fab")
		)
		(fp_line
			(start -0.12065 -0.2794)
			(end -0.12065 -0.3048)
			(stroke
				(width 0.1)
				(type default)
			)
			(layer "B.Fab")
		)
		(fp_line
			(start -0.120396 0.2794)
			(end 0.12065 0.2794)
			(stroke
				(width 0.1)
				(type default)
			)
			(layer "B.Fab")
		)
		(fp_line
			(start -0.120396 0.3048)
			(end -0.120396 0.2794)
			(stroke
				(width 0.1)
				(type default)
			)
			(layer "B.Fab")
		)
		(fp_line
			(start 0.12065 -0.305054)
			(end 0.12065 -0.2794)
			(stroke
				(width 0.1)
				(type default)
			)
			(layer "B.Fab")
		)
		(fp_line
			(start 0.12065 -0.2794)
			(end -0.12065 -0.2794)
			(stroke
				(width 0.1)
				(type default)
			)
			(layer "B.Fab")
		)
		(fp_line
			(start 0.12065 0.2794)
			(end 0.12065 0.3048)
			(stroke
				(width 0.1)
				(type default)
			)
			(layer "B.Fab")
		)
		(fp_line
			(start 0.12065 0.3048)
			(end 0.67945 0.3048)
			(stroke
				(width 0.1)
				(type default)
			)
			(layer "B.Fab")
		)
		(fp_line
			(start 0.67945 -0.305054)
			(end 0.12065 -0.305054)
			(stroke
				(width 0.1)
				(type default)
			)
			(layer "B.Fab")
		)
		(fp_line
			(start 0.67945 0.3048)
			(end 0.67945 -0.305054)
			(stroke
				(width 0.1)
				(type default)
			)
			(layer "B.Fab")
		)
		(pad "1" smd circle
			(at 0.40005 0 180)
			(size 0 0)
			(layers "B.Cu" "B.Mask" "B.Paste")
			(net "FM_PWRGD_P1V8_RETIMER_CPU0")
		)
		(pad "2" smd circle
			(at -0.40005 0 180)
			(size 0 0)
			(layers "B.Cu" "B.Mask" "B.Paste")
			(net "GND")
		)
	)
	(footprint ""
		(layer "B.Cu")
		(at 206.429356 -378.682504 180)
		(property "Reference" "PR2524"
			(at 0 0 0)
			(layer "B.SilkS")
			(hide yes)
			(effects
				(font
					(size 1.27 1.27)
				)
				(justify mirror)
			)
		)
		(property "Value" ""
			(at 0 0 0)
			(layer "B.Fab")
			(effects
				(font
					(size 1.27 1.27)
				)
				(justify mirror)
			)
		)
		(duplicate_pad_numbers_are_jumpers no)
		(fp_line
			(start 0.7874 0.4064)
			(end 0.7874 -0.4064)
			(stroke
				(width 0.1524)
				(type default)
			)
			(layer "B.SilkS")
		)
		(fp_line
			(start 0.7874 -0.4064)
			(end -0.7874 -0.4064)
			(stroke
				(width 0.1524)
				(type default)
			)
			(layer "B.SilkS")
		)
		(fp_line
			(start -0.7874 0.4064)
			(end 0.7874 0.4064)
			(stroke
				(width 0.1524)
				(type default)
			)
			(layer "B.SilkS")
		)
		(fp_line
			(start -0.7874 -0.4064)
			(end -0.7874 0.4064)
			(stroke
				(width 0.1524)
				(type default)
			)
			(layer "B.SilkS")
		)
		(fp_line
			(start 0.67945 0.3048)
			(end 0.67945 -0.305054)
			(stroke
				(width 0.1)
				(type default)
			)
			(layer "B.Fab")
		)
		(fp_line
			(start 0.67945 -0.305054)
			(end 0.12065 -0.305054)
			(stroke
				(width 0.1)
				(type default)
			)
			(layer "B.Fab")
		)
		(fp_line
			(start 0.12065 0.3048)
			(end 0.67945 0.3048)
			(stroke
				(width 0.1)
				(type default)
			)
			(layer "B.Fab")
		)
		(fp_line
			(start 0.12065 0.2794)
			(end 0.12065 0.3048)
			(stroke
				(width 0.1)
				(type default)
			)
			(layer "B.Fab")
		)
		(fp_line
			(start 0.12065 -0.2794)
			(end -0.12065 -0.2794)
			(stroke
				(width 0.1)
				(type default)
			)
			(layer "B.Fab")
		)
		(fp_line
			(start 0.12065 -0.305054)
			(end 0.12065 -0.2794)
			(stroke
				(width 0.1)
				(type default)
			)
			(layer "B.Fab")
		)
		(fp_line
			(start -0.120396 0.3048)
			(end -0.120396 0.2794)
			(stroke
				(width 0.1)
				(type default)
			)
			(layer "B.Fab")
		)
		(fp_line
			(start -0.120396 0.2794)
			(end 0.12065 0.2794)
			(stroke
				(width 0.1)
				(type default)
			)
			(layer "B.Fab")
		)
		(fp_line
			(start -0.12065 -0.2794)
			(end -0.12065 -0.3048)
			(stroke
				(width 0.1)
				(type default)
			)
			(layer "B.Fab")
		)
		(fp_line
			(start -0.12065 -0.3048)
			(end -0.67945 -0.3048)
			(stroke
				(width 0.1)
				(type default)
			)
			(layer "B.Fab")
		)
		(fp_line
			(start -0.67945 0.3048)
			(end -0.120396 0.3048)
			(stroke
				(width 0.1)
				(type default)
			)
			(layer "B.Fab")
		)
		(fp_line
			(start -0.67945 -0.3048)
			(end -0.67945 0.3048)
			(stroke
				(width 0.1)
				(type default)
			)
			(layer "B.Fab")
		)
		(pad "1" smd circle
			(at 0.40005 0)
			(size 0 0)
			(layers "B.Cu" "B.Mask" "B.Paste")
			(net "P12V_HSC_SENSE2_N")
		)
		(pad "2" smd circle
			(at -0.40005 0)
			(size 0 0)
			(layers "B.Cu" "B.Mask" "B.Paste")
			(net "P12V_HSC_SENSE2_R1_N")
		)
	)
	(footprint ""
		(layer "B.Cu")
		(at 187.511944 -117.442996 90)
		(property "Reference" "C1128"
			(at 0 0 90)
			(layer "B.SilkS")
			(hide yes)
			(effects
				(font
					(size 1.27 1.27)
				)
				(justify mirror)
			)
		)
		(property "Value" ""
			(at 0 0 90)
			(layer "B.Fab")
			(effects
				(font
					(size 1.27 1.27)
				)
				(justify mirror)
			)
		)
		(duplicate_pad_numbers_are_jumpers no)
		(fp_line
			(start 0.69215 -0.2921)
			(end -0.69215 -0.2921)
			(stroke
				(width 0.1524)
				(type default)
			)
			(layer "B.SilkS")
		)
		(fp_line
			(start -0.69215 -0.2921)
			(end -0.69215 0.2921)
			(stroke
				(width 0.1524)
				(type default)
			)
			(layer "B.SilkS")
		)
		(fp_line
			(start 0.69215 0.2921)
			(end 0.69215 -0.2921)
			(stroke
				(width 0.1524)
				(type default)
			)
			(layer "B.SilkS")
		)
		(fp_line
			(start -0.69215 0.2921)
			(end 0.69215 0.2921)
			(stroke
				(width 0.1524)
				(type default)
			)
			(layer "B.SilkS")
		)
		(fp_line
			(start 0.51435 -0.2794)
			(end -0.51435 -0.2794)
			(stroke
				(width 0.1)
				(type default)
			)
			(layer "B.Fab")
		)
		(fp_line
			(start -0.51435 -0.2794)
			(end -0.51435 0.2794)
			(stroke
				(width 0.1)
				(type default)
			)
			(layer "B.Fab")
		)
		(fp_line
			(start 0.51435 0.2794)
			(end 0.51435 -0.2794)
			(stroke
				(width 0.1)
				(type default)
			)
			(layer "B.Fab")
		)
		(fp_line
			(start -0.51435 0.2794)
			(end 0.51435 0.2794)
			(stroke
				(width 0.1)
				(type default)
			)
			(layer "B.Fab")
		)
		(pad "1" smd circle
			(at 0.40005 0 270)
			(size 0 0)
			(layers "B.Cu" "B.Mask" "B.Paste")
			(net "P1V8_AUX")
		)
		(pad "2" smd circle
			(at -0.40005 0 270)
			(size 0 0)
			(layers "B.Cu" "B.Mask" "B.Paste")
			(net "GND")
		)
		(zone
			(layer "B.Cu")
			(hatch none 0.5)
			(connect_pads
				(clearance 0)
			)
			(min_thickness 0.25)
			(keepout
				(tracks not_allowed)
				(vias allowed)
				(pads allowed)
				(copperpour not_allowed)
				(footprints allowed)
			)
			(placement
				(enabled no)
				(sheetname "")
			)
			(fill
				(thermal_gap 0.5)
				(thermal_bridge_width 0.5)
				(island_removal_mode 0)
			)
			(polygon
				(pts
					(xy 187.365894 -117.342666) (xy 187.365894 -117.542056) (xy 187.42406 -117.633496) (xy 187.599574 -117.633496)
					(xy 187.65774 -117.542056) (xy 187.65774 -117.342666) (xy 187.599574 -117.252496) (xy 187.424314 -117.252496)
				)
			)
		)
	)
	(footprint ""
		(layer "B.Cu")
		(at 213.285578 -326.509888)
		(property "Reference" "C1095"
			(at 0 0 0)
			(layer "B.SilkS")
			(hide yes)
			(effects
				(font
					(size 1.27 1.27)
				)
				(justify mirror)
			)
		)
		(property "Value" ""
			(at 0 0 0)
			(layer "B.Fab")
			(effects
				(font
					(size 1.27 1.27)
				)
				(justify mirror)
			)
		)
		(duplicate_pad_numbers_are_jumpers no)
		(fp_line
			(start -0.7874 -0.4064)
			(end -0.7874 0.4064)
			(stroke
				(width 0.1524)
				(type default)
			)
			(layer "B.SilkS")
		)
		(fp_line
			(start -0.7874 0.4064)
			(end 0.7874 0.4064)
			(stroke
				(width 0.1524)
				(type default)
			)
			(layer "B.SilkS")
		)
		(fp_line
			(start 0.7874 -0.4064)
			(end -0.7874 -0.4064)
			(stroke
				(width 0.1524)
				(type default)
			)
			(layer "B.SilkS")
		)
		(fp_line
			(start 0.7874 0.4064)
			(end 0.7874 -0.4064)
			(stroke
				(width 0.1524)
				(type default)
			)
			(layer "B.SilkS")
		)
		(fp_line
			(start -0.67945 -0.3048)
			(end -0.67945 0.3048)
			(stroke
				(width 0.1)
				(type default)
			)
			(layer "B.Fab")
		)
		(fp_line
			(start -0.67945 0.3048)
			(end -0.120396 0.3048)
			(stroke
				(width 0.1)
				(type default)
			)
			(layer "B.Fab")
		)
		(fp_line
			(start -0.12065 -0.3048)
			(end -0.67945 -0.3048)
			(stroke
				(width 0.1)
				(type default)
			)
			(layer "B.Fab")
		)
		(fp_line
			(start -0.12065 -0.2794)
			(end -0.12065 -0.3048)
			(stroke
				(width 0.1)
				(type default)
			)
			(layer "B.Fab")
		)
		(fp_line
			(start -0.120396 0.2794)
			(end 0.12065 0.2794)
			(stroke
				(width 0.1)
				(type default)
			)
			(layer "B.Fab")
		)
		(fp_line
			(start -0.120396 0.3048)
			(end -0.120396 0.2794)
			(stroke
				(width 0.1)
				(type default)
			)
			(layer "B.Fab")
		)
		(fp_line
			(start 0.12065 -0.305054)
			(end 0.12065 -0.2794)
			(stroke
				(width 0.1)
				(type default)
			)
			(layer "B.Fab")
		)
		(fp_line
			(start 0.12065 -0.2794)
			(end -0.12065 -0.2794)
			(stroke
				(width 0.1)
				(type default)
			)
			(layer "B.Fab")
		)
		(fp_line
			(start 0.12065 0.2794)
			(end 0.12065 0.3048)
			(stroke
				(width 0.1)
				(type default)
			)
			(layer "B.Fab")
		)
		(fp_line
			(start 0.12065 0.3048)
			(end 0.67945 0.3048)
			(stroke
				(width 0.1)
				(type default)
			)
			(layer "B.Fab")
		)
		(fp_line
			(start 0.67945 -0.305054)
			(end 0.12065 -0.305054)
			(stroke
				(width 0.1)
				(type default)
			)
			(layer "B.Fab")
		)
		(fp_line
			(start 0.67945 0.3048)
			(end 0.67945 -0.305054)
			(stroke
				(width 0.1)
				(type default)
			)
			(layer "B.Fab")
		)
		(pad "1" smd circle
			(at 0.40005 0 180)
			(size 0 0)
			(layers "B.Cu" "B.Mask" "B.Paste")
			(net "P3V3_ADC128_2_VCC")
		)
		(pad "2" smd circle
			(at -0.40005 0 180)
			(size 0 0)
			(layers "B.Cu" "B.Mask" "B.Paste")
			(net "GND")
		)
	)
	(footprint ""
		(layer "B.Cu")
		(at 206.429356 -385.136136 180)
		(property "Reference" "PR2521"
			(at 0 0 0)
			(layer "B.SilkS")
			(hide yes)
			(effects
				(font
					(size 1.27 1.27)
				)
				(justify mirror)
			)
		)
		(property "Value" ""
			(at 0 0 0)
			(layer "B.Fab")
			(effects
				(font
					(size 1.27 1.27)
				)
				(justify mirror)
			)
		)
		(duplicate_pad_numbers_are_jumpers no)
		(fp_line
			(start 0.7874 0.4064)
			(end 0.7874 -0.4064)
			(stroke
				(width 0.1524)
				(type default)
			)
			(layer "B.SilkS")
		)
		(fp_line
			(start 0.7874 -0.4064)
			(end -0.7874 -0.4064)
			(stroke
				(width 0.1524)
				(type default)
			)
			(layer "B.SilkS")
		)
		(fp_line
			(start -0.7874 0.4064)
			(end 0.7874 0.4064)
			(stroke
				(width 0.1524)
				(type default)
			)
			(layer "B.SilkS")
		)
		(fp_line
			(start -0.7874 -0.4064)
			(end -0.7874 0.4064)
			(stroke
				(width 0.1524)
				(type default)
			)
			(layer "B.SilkS")
		)
		(fp_line
			(start 0.67945 0.3048)
			(end 0.67945 -0.305054)
			(stroke
				(width 0.1)
				(type default)
			)
			(layer "B.Fab")
		)
		(fp_line
			(start 0.67945 -0.305054)
			(end 0.12065 -0.305054)
			(stroke
				(width 0.1)
				(type default)
			)
			(layer "B.Fab")
		)
		(fp_line
			(start 0.12065 0.3048)
			(end 0.67945 0.3048)
			(stroke
				(width 0.1)
				(type default)
			)
			(layer "B.Fab")
		)
		(fp_line
			(start 0.12065 0.2794)
			(end 0.12065 0.3048)
			(stroke
				(width 0.1)
				(type default)
			)
			(layer "B.Fab")
		)
		(fp_line
			(start 0.12065 -0.2794)
			(end -0.12065 -0.2794)
			(stroke
				(width 0.1)
				(type default)
			)
			(layer "B.Fab")
		)
		(fp_line
			(start 0.12065 -0.305054)
			(end 0.12065 -0.2794)
			(stroke
				(width 0.1)
				(type default)
			)
			(layer "B.Fab")
		)
		(fp_line
			(start -0.120396 0.3048)
			(end -0.120396 0.2794)
			(stroke
				(width 0.1)
				(type default)
			)
			(layer "B.Fab")
		)
		(fp_line
			(start -0.120396 0.2794)
			(end 0.12065 0.2794)
			(stroke
				(width 0.1)
				(type default)
			)
			(layer "B.Fab")
		)
		(fp_line
			(start -0.12065 -0.2794)
			(end -0.12065 -0.3048)
			(stroke
				(width 0.1)
				(type default)
			)
			(layer "B.Fab")
		)
		(fp_line
			(start -0.12065 -0.3048)
			(end -0.67945 -0.3048)
			(stroke
				(width 0.1)
				(type default)
			)
			(layer "B.Fab")
		)
		(fp_line
			(start -0.67945 0.3048)
			(end -0.120396 0.3048)
			(stroke
				(width 0.1)
				(type default)
			)
			(layer "B.Fab")
		)
		(fp_line
			(start -0.67945 -0.3048)
			(end -0.67945 0.3048)
			(stroke
				(width 0.1)
				(type default)
			)
			(layer "B.Fab")
		)
		(pad "1" smd circle
			(at 0.40005 0)
			(size 0 0)
			(layers "B.Cu" "B.Mask" "B.Paste")
			(net "P12V_HSC_SENSE2_P")
		)
		(pad "2" smd circle
			(at -0.40005 0)
			(size 0 0)
			(layers "B.Cu" "B.Mask" "B.Paste")
			(net "P12V_HSC_SENSE2_R2_P")
		)
	)
)
